# T6G (Grand Teton) — schematic netlist excerpt (pin names and nets, part order shuffled) for the footprints in the layout excerpt that follows; sources: Cadence DE-HDL packaged netlist, KiCad conversion of 04192023_DAF0TMB3IC0_F0TG_MB_C_brd_V02_OCP.brd

R3175  Q_RES  10K 1% CHIP  pkg 0402LF  page 137 : A = SGPIO_OCP_V3_2_DATAOUT ; B = GND
C3922  Q_CAP  22UF 4V 20% X6S  pkg C0402  page 74 : A = PVDD11_S3_P1 ; B = GND

(kicad_pcb
	(version 20260206)
	(generator "pcbnew")
	(generator_version "10.0")
	(general
		(thickness 1.6)
		(legacy_teardrops no)
	)
	(paper "A4")
	(title_block
		(title "04192023_DAF0TMB3IC0_F0TG_MB_C_brd_V02_OCP.brd")
		(comment 1 "Grand Teton / footprints 8227-8228 of 8354")
	)
	(layers
		(0 "F.Cu" signal "TOP")
		(4 "In1.Cu" signal "GND")
		(6 "In2.Cu" signal "IN1")
		(8 "In3.Cu" signal "GND1")
		(10 "In4.Cu" signal "IN2")
		(12 "In5.Cu" signal "GND2")
		(14 "In6.Cu" signal "IN3")
		(16 "In7.Cu" signal "GND3")
		(18 "In8.Cu" signal "VCC")
		(20 "In9.Cu" signal "VCC1")
		(22 "In10.Cu" signal "GND4")
		(24 "In11.Cu" signal "IN4")
		(26 "In12.Cu" signal "GND5")
		(28 "In13.Cu" signal "IN5")
		(30 "In14.Cu" signal "GND6")
		(32 "In15.Cu" signal "IN6")
		(34 "In16.Cu" signal "GND7")
		(2 "B.Cu" signal "BOTTOM")
		(9 "F.Adhes" user "F.Adhesive")
		(11 "B.Adhes" user "B.Adhesive")
		(13 "F.Paste" user "Package Geometry/Pastemask Top")
		(15 "B.Paste" user "Package Geometry/Pastemask Bottom")
		(5 "F.SilkS" user "Ref Des/Silkscreen Top")
		(7 "B.SilkS" user "Ref Des/Silkscreen Bottom")
		(1 "F.Mask" user "Board Geometry/Soldermask Top")
		(3 "B.Mask" user "Board Geometry/Soldermask Bottom")
		(17 "Dwgs.User" user "User.Drawings")
		(19 "Cmts.User" user "User.Comments")
		(21 "Eco1.User" user "User.Eco1")
		(23 "Eco2.User" user "User.Eco2")
		(25 "Edge.Cuts" user "Board Geometry/Outline")
		(27 "Margin" user)
		(31 "F.CrtYd" user "Package Geometry/Place Bound Top")
		(29 "B.CrtYd" user "Package Geometry/Place Bound Bottom")
		(35 "F.Fab" user "Ref Des/Assembly Top")
		(33 "B.Fab" user "Ref Des/Assembly Bottom")
	)
	(footprint ""
		(layer "B.Cu")
		(at 73.695814 -9.50468)
		(property "Reference" "R3175"
			(at 0 0 0)
			(layer "B.SilkS")
			(hide yes)
			(effects
				(font
					(size 1.27 1.27)
				)
				(justify mirror)
			)
		)
		(property "Value" ""
			(at 0 0 0)
			(layer "B.Fab")
			(effects
				(font
					(size 1.27 1.27)
				)
				(justify mirror)
			)
		)
		(duplicate_pad_numbers_are_jumpers no)
		(fp_line
			(start -0.7874 -0.4064)
			(end -0.7874 0.4064)
			(stroke
				(width 0.1524)
				(type default)
			)
			(layer "B.SilkS")
		)
		(fp_line
			(start -0.7874 0.4064)
			(end 0.7874 0.4064)
			(stroke
				(width 0.1524)
				(type default)
			)
			(layer "B.SilkS")
		)
		(fp_line
			(start 0.7874 -0.4064)
			(end -0.7874 -0.4064)
			(stroke
				(width 0.1524)
				(type default)
			)
			(layer "B.SilkS")
		)
		(fp_line
			(start 0.7874 0.4064)
			(end 0.7874 -0.4064)
			(stroke
				(width 0.1524)
				(type default)
			)
			(layer "B.SilkS")
		)
		(fp_line
			(start -0.67945 -0.3048)
			(end -0.67945 0.3048)
			(stroke
				(width 0.1)
				(type default)
			)
			(layer "B.Fab")
		)
		(fp_line
			(start -0.67945 0.3048)
			(end -0.120396 0.3048)
			(stroke
				(width 0.1)
				(type default)
			)
			(layer "B.Fab")
		)
		(fp_line
			(start -0.12065 -0.3048)
			(end -0.67945 -0.3048)
			(stroke
				(width 0.1)
				(type default)
			)
			(layer "B.Fab")
		)
		(fp_line
			(start -0.12065 -0.2794)
			(end -0.12065 -0.3048)
			(stroke
				(width 0.1)
				(type default)
			)
			(layer "B.Fab")
		)
		(fp_line
			(start -0.120396 0.2794)
			(end 0.12065 0.2794)
			(stroke
				(width 0.1)
				(type default)
			)
			(layer "B.Fab")
		)
		(fp_line
			(start -0.120396 0.3048)
			(end -0.120396 0.2794)
			(stroke
				(width 0.1)
				(type default)
			)
			(layer "B.Fab")
		)
		(fp_line
			(start 0.12065 -0.305054)
			(end 0.12065 -0.2794)
			(stroke
				(width 0.1)
				(type default)
			)
			(layer "B.Fab")
		)
		(fp_line
			(start 0.12065 -0.2794)
			(end -0.12065 -0.2794)
			(stroke
				(width 0.1)
				(type default)
			)
			(layer "B.Fab")
		)
		(fp_line
			(start 0.12065 0.2794)
			(end 0.12065 0.3048)
			(stroke
				(width 0.1)
				(type default)
			)
			(layer "B.Fab")
		)
		(fp_line
			(start 0.12065 0.3048)
			(end 0.67945 0.3048)
			(stroke
				(width 0.1)
				(type default)
			)
			(layer "B.Fab")
		)
		(fp_line
			(start 0.67945 -0.305054)
			(end 0.12065 -0.305054)
			(stroke
				(width 0.1)
				(type default)
			)
			(layer "B.Fab")
		)
		(fp_line
			(start 0.67945 0.3048)
			(end 0.67945 -0.305054)
			(stroke
				(width 0.1)
				(type default)
			)
			(layer "B.Fab")
		)
		(pad "1" smd circle
			(at 0.40005 0 180)
			(size 0 0)
			(layers "B.Cu" "B.Mask" "B.Paste")
			(net "SGPIO_OCP_V3_2_DATAOUT")
		)
		(pad "2" smd circle
			(at -0.40005 0 180)
			(size 0 0)
			(layers "B.Cu" "B.Mask" "B.Paste")
			(net "GND")
		)
	)
	(footprint ""
		(layer "B.Cu")
		(at 100.878386 -266.005564)
		(property "Reference" "C3922"
			(at 0 0 0)
			(layer "B.SilkS")
			(hide yes)
			(effects
				(font
					(size 1.27 1.27)
				)
				(justify mirror)
			)
		)
		(property "Value" ""
			(at 0 0 0)
			(layer "B.Fab")
			(effects
				(font
					(size 1.27 1.27)
				)
				(justify mirror)
			)
		)
		(duplicate_pad_numbers_are_jumpers no)
		(fp_line
			(start -0.7874 -0.4064)
			(end -0.7874 0.4064)
			(stroke
				(width 0.1524)
				(type default)
			)
			(layer "B.SilkS")
		)
		(fp_line
			(start -0.7874 0.4064)
			(end 0.7874 0.4064)
			(stroke
				(width 0.1524)
				(type default)
			)
			(layer "B.SilkS")
		)
		(fp_line
			(start 0.7874 -0.4064)
			(end -0.7874 -0.4064)
			(stroke
				(width 0.1524)
				(type default)
			)
			(layer "B.SilkS")
		)
		(fp_line
			(start 0.7874 0.4064)
			(end 0.7874 -0.4064)
			(stroke
				(width 0.1524)
				(type default)
			)
			(layer "B.SilkS")
		)
		(fp_line
			(start -0.67945 -0.3048)
			(end -0.67945 0.3048)
			(stroke
				(width 0.1)
				(type default)
			)
			(layer "B.Fab")
		)
		(fp_line
			(start -0.67945 0.3048)
			(end -0.120396 0.3048)
			(stroke
				(width 0.1)
				(type default)
			)
			(layer "B.Fab")
		)
		(fp_line
			(start -0.12065 -0.3048)
			(end -0.67945 -0.3048)
			(stroke
				(width 0.1)
				(type default)
			)
			(layer "B.Fab")
		)
		(fp_line
			(start -0.12065 -0.2794)
			(end -0.12065 -0.3048)
			(stroke
				(width 0.1)
				(type default)
			)
			(layer "B.Fab")
		)
		(fp_line
			(start -0.120396 0.2794)
			(end 0.12065 0.2794)
			(stroke
				(width 0.1)
				(type default)
			)
			(layer "B.Fab")
		)
		(fp_line
			(start -0.120396 0.3048)
			(end -0.120396 0.2794)
			(stroke
				(width 0.1)
				(type default)
			)
			(layer "B.Fab")
		)
		(fp_line
			(start 0.12065 -0.305054)
			(end 0.12065 -0.2794)
			(stroke
				(width 0.1)
				(type default)
			)
			(layer "B.Fab")
		)
		(fp_line
			(start 0.12065 -0.2794)
			(end -0.12065 -0.2794)
			(stroke
				(width 0.1)
				(type default)
			)
			(layer "B.Fab")
		)
		(fp_line
			(start 0.12065 0.2794)
			(end 0.12065 0.3048)
			(stroke
				(width 0.1)
				(type default)
			)
			(layer "B.Fab")
		)
		(fp_line
			(start 0.12065 0.3048)
			(end 0.67945 0.3048)
			(stroke
				(width 0.1)
				(type default)
			)
			(layer "B.Fab")
		)
		(fp_line
			(start 0.67945 -0.305054)
			(end 0.12065 -0.305054)
			(stroke
				(width 0.1)
				(type default)
			)
			(layer "B.Fab")
		)
		(fp_line
			(start 0.67945 0.3048)
			(end 0.67945 -0.305054)
			(stroke
				(width 0.1)
				(type default)
			)
			(layer "B.Fab")
		)
		(pad "1" smd circle
			(at 0.40005 0 180)
			(size 0 0)
			(layers "B.Cu" "B.Mask" "B.Paste")
			(net "PVDD11_S3_P1")
		)
		(pad "2" smd circle
			(at -0.40005 0 180)
			(size 0 0)
			(layers "B.Cu" "B.Mask" "B.Paste")
			(net "GND")
		)
	)
)
